# S9S_MB_2U (Grand Teton) — schematic netlist excerpt (pin names and nets, part order shuffled) for the footprints in the layout excerpt that follows; sources: Cadence DE-HDL packaged netlist, KiCad conversion of 03242023_DA0F0TMBIJ0_F0T_Motherboard_J_brd_V01_OCP.brd

DB4  TDR_3P  EMPTY  pkg TH2  page 309
  GND  = T1_GND
  IO1  = TDR_SE_40_OHM_IN3
  IO2  = TDR_SE_40_OHM_IN3

R3393  Q_RES  0 5% CHIP  pkg 0402LF  page 231 : A = SMB_IOEXP_3V3AUX_SCL_R ; B = SMB_IOEXP_3V3AUX_SCL
R2597  Q_RES  0 5% CHIP  pkg 0402LF  page 274 : A = IRQ_PVCCFA_CPU0_VRHOT_N ; B = IRQ_PVCCFA_CPU0_VRHOT_R_N

(kicad_pcb
	(version 20260206)
	(generator "pcbnew")
	(generator_version "10.0")
	(general
		(thickness 1.6)
		(legacy_teardrops no)
	)
	(paper "A4")
	(title_block
		(title "03242023_DA0F0TMBIJ0_F0T_Motherboard_J_brd_V01_OCP.brd")
		(comment 1 "Grand Teton / footprints 2226-2228 of 6105")
	)
	(layers
		(0 "F.Cu" signal "TOP")
		(4 "In1.Cu" signal "GND")
		(6 "In2.Cu" signal "IN1")
		(8 "In3.Cu" signal "GND1")
		(10 "In4.Cu" signal "IN2")
		(12 "In5.Cu" signal "GND2")
		(14 "In6.Cu" signal "IN3")
		(16 "In7.Cu" signal "GND3")
		(18 "In8.Cu" signal "VCC")
		(20 "In9.Cu" signal "VCC1")
		(22 "In10.Cu" signal "GND4")
		(24 "In11.Cu" signal "IN4")
		(26 "In12.Cu" signal "GND5")
		(28 "In13.Cu" signal "IN5")
		(30 "In14.Cu" signal "GND6")
		(32 "In15.Cu" signal "IN6")
		(34 "In16.Cu" signal "GND7")
		(2 "B.Cu" signal "BOTTOM")
		(9 "F.Adhes" user "F.Adhesive")
		(11 "B.Adhes" user "B.Adhesive")
		(13 "F.Paste" user "Package Geometry/Pastemask Top")
		(15 "B.Paste" user "Package Geometry/Pastemask Bottom")
		(5 "F.SilkS" user "Ref Des/Silkscreen Top")
		(7 "B.SilkS" user "Ref Des/Silkscreen Bottom")
		(1 "F.Mask" user "Board Geometry/Soldermask Top")
		(3 "B.Mask" user "Board Geometry/Soldermask Bottom")
		(17 "Dwgs.User" user "User.Drawings")
		(19 "Cmts.User" user "User.Comments")
		(21 "Eco1.User" user "User.Eco1")
		(23 "Eco2.User" user "User.Eco2")
		(25 "Edge.Cuts" user "Board Geometry/Outline")
		(27 "Margin" user)
		(31 "F.CrtYd" user "Package Geometry/Place Bound Top")
		(29 "B.CrtYd" user "Package Geometry/Place Bound Bottom")
		(35 "F.Fab" user "Ref Des/Assembly Top")
		(33 "B.Fab" user "Ref Des/Assembly Bottom")
	)
	(footprint ""
		(layer "F.Cu")
		(at 113.494312 -132.456682 180)
		(property "Reference" "R3393"
			(at 0 0 180)
			(layer "F.SilkS")
			(hide yes)
			(effects
				(font
					(size 1.27 1.27)
				)
			)
		)
		(property "Value" ""
			(at 0 0 180)
			(layer "F.Fab")
			(effects
				(font
					(size 1.27 1.27)
				)
			)
		)
		(duplicate_pad_numbers_are_jumpers no)
		(fp_line
			(start 0.7874 0.4064)
			(end -0.7874 0.4064)
			(stroke
				(width 0.1524)
				(type default)
			)
			(layer "F.SilkS")
		)
		(fp_line
			(start 0.7874 -0.4064)
			(end 0.7874 0.4064)
			(stroke
				(width 0.1524)
				(type default)
			)
			(layer "F.SilkS")
		)
		(fp_line
			(start -0.7874 0.4064)
			(end -0.7874 -0.4064)
			(stroke
				(width 0.1524)
				(type default)
			)
			(layer "F.SilkS")
		)
		(fp_line
			(start -0.7874 -0.4064)
			(end 0.7874 -0.4064)
			(stroke
				(width 0.1524)
				(type default)
			)
			(layer "F.SilkS")
		)
		(fp_line
			(start 0.67945 0.3048)
			(end 0.120396 0.3048)
			(stroke
				(width 0.1)
				(type default)
			)
			(layer "F.Fab")
		)
		(fp_line
			(start 0.67945 -0.3048)
			(end 0.67945 0.3048)
			(stroke
				(width 0.1)
				(type default)
			)
			(layer "F.Fab")
		)
		(fp_line
			(start 0.12065 -0.2794)
			(end 0.12065 -0.3048)
			(stroke
				(width 0.1)
				(type default)
			)
			(layer "F.Fab")
		)
		(fp_line
			(start 0.12065 -0.3048)
			(end 0.67945 -0.3048)
			(stroke
				(width 0.1)
				(type default)
			)
			(layer "F.Fab")
		)
		(fp_line
			(start 0.120396 0.3048)
			(end 0.120396 0.2794)
			(stroke
				(width 0.1)
				(type default)
			)
			(layer "F.Fab")
		)
		(fp_line
			(start 0.120396 0.2794)
			(end -0.12065 0.2794)
			(stroke
				(width 0.1)
				(type default)
			)
			(layer "F.Fab")
		)
		(fp_line
			(start -0.12065 0.3048)
			(end -0.67945 0.3048)
			(stroke
				(width 0.1)
				(type default)
			)
			(layer "F.Fab")
		)
		(fp_line
			(start -0.12065 0.2794)
			(end -0.12065 0.3048)
			(stroke
				(width 0.1)
				(type default)
			)
			(layer "F.Fab")
		)
		(fp_line
			(start -0.12065 -0.2794)
			(end 0.12065 -0.2794)
			(stroke
				(width 0.1)
				(type default)
			)
			(layer "F.Fab")
		)
		(fp_line
			(start -0.12065 -0.305054)
			(end -0.12065 -0.2794)
			(stroke
				(width 0.1)
				(type default)
			)
			(layer "F.Fab")
		)
		(fp_line
			(start -0.67945 0.3048)
			(end -0.67945 -0.305054)
			(stroke
				(width 0.1)
				(type default)
			)
			(layer "F.Fab")
		)
		(fp_line
			(start -0.67945 -0.305054)
			(end -0.12065 -0.305054)
			(stroke
				(width 0.1)
				(type default)
			)
			(layer "F.Fab")
		)
		(pad "1" smd circle
			(at -0.40005 0 180)
			(size 0 0)
			(layers "F.Cu" "F.Mask" "F.Paste")
			(net "SMB_IOEXP_3V3AUX_SCL_R")
		)
		(pad "2" smd circle
			(at 0.40005 0 180)
			(size 0 0)
			(layers "F.Cu" "F.Mask" "F.Paste")
			(net "SMB_IOEXP_3V3AUX_SCL")
		)
	)
	(footprint ""
		(layer "F.Cu")
		(at 430.600104 -135.510778)
		(property "Reference" "R2597"
			(at 0 0 0)
			(layer "F.SilkS")
			(hide yes)
			(effects
				(font
					(size 1.27 1.27)
				)
			)
		)
		(property "Value" ""
			(at 0 0 0)
			(layer "F.Fab")
			(effects
				(font
					(size 1.27 1.27)
				)
			)
		)
		(duplicate_pad_numbers_are_jumpers no)
		(fp_line
			(start -0.7874 -0.4064)
			(end 0.7874 -0.4064)
			(stroke
				(width 0.1524)
				(type default)
			)
			(layer "F.SilkS")
		)
		(fp_line
			(start -0.7874 0.4064)
			(end -0.7874 -0.4064)
			(stroke
				(width 0.1524)
				(type default)
			)
			(layer "F.SilkS")
		)
		(fp_line
			(start 0.7874 -0.4064)
			(end 0.7874 0.4064)
			(stroke
				(width 0.1524)
				(type default)
			)
			(layer "F.SilkS")
		)
		(fp_line
			(start 0.7874 0.4064)
			(end -0.7874 0.4064)
			(stroke
				(width 0.1524)
				(type default)
			)
			(layer "F.SilkS")
		)
		(fp_line
			(start -0.67945 -0.305054)
			(end -0.12065 -0.305054)
			(stroke
				(width 0.1)
				(type default)
			)
			(layer "F.Fab")
		)
		(fp_line
			(start -0.67945 0.3048)
			(end -0.67945 -0.305054)
			(stroke
				(width 0.1)
				(type default)
			)
			(layer "F.Fab")
		)
		(fp_line
			(start -0.12065 -0.305054)
			(end -0.12065 -0.2794)
			(stroke
				(width 0.1)
				(type default)
			)
			(layer "F.Fab")
		)
		(fp_line
			(start -0.12065 -0.2794)
			(end 0.12065 -0.2794)
			(stroke
				(width 0.1)
				(type default)
			)
			(layer "F.Fab")
		)
		(fp_line
			(start -0.12065 0.2794)
			(end -0.12065 0.3048)
			(stroke
				(width 0.1)
				(type default)
			)
			(layer "F.Fab")
		)
		(fp_line
			(start -0.12065 0.3048)
			(end -0.67945 0.3048)
			(stroke
				(width 0.1)
				(type default)
			)
			(layer "F.Fab")
		)
		(fp_line
			(start 0.120396 0.2794)
			(end -0.12065 0.2794)
			(stroke
				(width 0.1)
				(type default)
			)
			(layer "F.Fab")
		)
		(fp_line
			(start 0.120396 0.3048)
			(end 0.120396 0.2794)
			(stroke
				(width 0.1)
				(type default)
			)
			(layer "F.Fab")
		)
		(fp_line
			(start 0.12065 -0.3048)
			(end 0.67945 -0.3048)
			(stroke
				(width 0.1)
				(type default)
			)
			(layer "F.Fab")
		)
		(fp_line
			(start 0.12065 -0.2794)
			(end 0.12065 -0.3048)
			(stroke
				(width 0.1)
				(type default)
			)
			(layer "F.Fab")
		)
		(fp_line
			(start 0.67945 -0.3048)
			(end 0.67945 0.3048)
			(stroke
				(width 0.1)
				(type default)
			)
			(layer "F.Fab")
		)
		(fp_line
			(start 0.67945 0.3048)
			(end 0.120396 0.3048)
			(stroke
				(width 0.1)
				(type default)
			)
			(layer "F.Fab")
		)
		(pad "1" smd circle
			(at -0.40005 0)
			(size 0 0)
			(layers "F.Cu" "F.Mask" "F.Paste")
			(net "IRQ_PVCCFA_CPU0_VRHOT_N")
		)
		(pad "2" smd circle
			(at 0.40005 0)
			(size 0 0)
			(layers "F.Cu" "F.Mask" "F.Paste")
			(net "IRQ_PVCCFA_CPU0_VRHOT_R_N")
		)
	)
	(footprint ""
		(layer "F.Cu")
		(at 495.422936 -427.608238 180)
		(property "Reference" "DB4"
			(at -2.717546 -0.136906 90)
			(unlocked yes)
			(layer "F.SilkS")
			(effects
				(font
					(size 0.7874 0.5842)
					(thickness 0.1524)
				)
				(justify left)
			)
		)
		(property "Value" ""
			(at 0 0 180)
			(layer "F.Fab")
			(effects
				(font
					(size 1.27 1.27)
				)
			)
		)
		(duplicate_pad_numbers_are_jumpers no)
		(fp_line
			(start 3.330702 -4.771136)
			(end 3.21564 -4.46786)
			(stroke
				(width 0.1524)
				(type default)
			)
			(layer "F.SilkS")
		)
		(fp_line
			(start 2.502916 -2.588514)
			(end 0 4.011168)
			(stroke
				(width 0.1524)
				(type default)
			)
			(layer "F.SilkS")
		)
		(fp_line
			(start 0 4.011168)
			(end -3.330702 -4.771136)
			(stroke
				(width 0.1524)
				(type default)
			)
			(layer "F.SilkS")
		)
		(fp_line
			(start -3.330702 -4.771136)
			(end 3.330702 -4.771136)
			(stroke
				(width 0.1524)
				(type default)
			)
			(layer "F.SilkS")
		)
		(fp_line
			(start 3.330702 -4.771136)
			(end 0 4.011168)
			(stroke
				(width 0.1)
				(type default)
			)
			(layer "F.Fab")
		)
		(fp_line
			(start 0 4.011168)
			(end -3.330702 -4.771136)
			(stroke
				(width 0.1)
				(type default)
			)
			(layer "F.Fab")
		)
		(fp_line
			(start -3.330702 -4.771136)
			(end 3.330702 -4.771136)
			(stroke
				(width 0.1)
				(type default)
			)
			(layer "F.Fab")
		)
		(pad "1" thru_hole circle
			(at 0 0 180)
			(size 2.159 2.159)
			(drill 1.7018)
			(layers "*.Cu" "*.Mask")
			(remove_unused_layers no)
			(net "T1_GND")
			(clearance 0.0254)
			(thermal_gap 0.0254)
		)
		(pad "2" thru_hole circle
			(at -1.27 -3.348736 180)
			(size 2.159 2.159)
			(drill 1.7018)
			(layers "*.Cu" "*.Mask")
			(remove_unused_layers no)
			(net "TDR_SE_40_OHM_IN3")
			(clearance 0.0254)
			(thermal_gap 0.0254)
		)
		(pad "3" thru_hole circle
			(at 1.27 -3.348736 180)
			(size 2.159 2.159)
			(drill 1.7018)
			(layers "*.Cu" "*.Mask")
			(remove_unused_layers no)
			(net "TDR_SE_40_OHM_IN3")
			(clearance 0.0254)
			(thermal_gap 0.0254)
		)
	)
)
